# BASEBOARD_FAB2 (Tioga Pass) — schematic netlist excerpt (pin names and nets, part order shuffled) for the footprints in the layout excerpt that follows; sources: Cadence DE-HDL packaged netlist, KiCad conversion of Wiwynn_Tioga_Pass_MB.brd

R1C34  RES  10.0K 1% CHIP  pkg 0402  page 156 : A = P3V3_STBY ; B = PU_PIROM_CPU1_ADDR0
R12W14  RES  100.0K 1% CHIP  pkg 0603  page 197 : A = P12V_NVDIMM_GHJ ; B = PWRGD_PVDDQ_GHJ_N
R8F35  RES  1.00K 1% EMPTY  pkg 0402  page 162 : A = PU_SPI_BMC_BT_WP_N ; B = GND

(kicad_pcb
	(version 20260206)
	(generator "pcbnew")
	(generator_version "10.0")
	(general
		(thickness 1.6)
		(legacy_teardrops no)
	)
	(paper "A4")
	(title_block
		(title "Wiwynn_Tioga_Pass_MB.brd")
		(comment 1 "Tioga Pass / footprints 104-106 of 4770")
	)
	(layers
		(0 "F.Cu" signal "TOP")
		(4 "In1.Cu" signal "L2GND")
		(6 "In2.Cu" signal "L3")
		(8 "In3.Cu" signal "L4GND")
		(10 "In4.Cu" signal "L5")
		(12 "In5.Cu" signal "L6GND")
		(14 "In6.Cu" signal "L7VCC")
		(16 "In7.Cu" signal "L8VCC")
		(18 "In8.Cu" signal "L9GND")
		(20 "In9.Cu" signal "L10")
		(22 "In10.Cu" signal "L11GND")
		(24 "In11.Cu" signal "L12")
		(26 "In12.Cu" signal "L13GND")
		(2 "B.Cu" signal "BOTTOM")
		(9 "F.Adhes" user "F.Adhesive")
		(11 "B.Adhes" user "B.Adhesive")
		(13 "F.Paste" user "Package Geometry/Pastemask Top")
		(15 "B.Paste" user "Package Geometry/Pastemask Bottom")
		(5 "F.SilkS" user "Ref Des/Silkscreen Top")
		(7 "B.SilkS" user "Ref Des/Silkscreen Bottom")
		(1 "F.Mask" user "Board Geometry/Soldermask Top")
		(3 "B.Mask" user "Board Geometry/Soldermask Bottom")
		(17 "Dwgs.User" user "User.Drawings")
		(19 "Cmts.User" user "User.Comments")
		(21 "Eco1.User" user "User.Eco1")
		(23 "Eco2.User" user "User.Eco2")
		(25 "Edge.Cuts" user "Board Geometry/Outline")
		(27 "Margin" user)
		(31 "F.CrtYd" user "Package Geometry/Place Bound Top")
		(29 "B.CrtYd" user "Package Geometry/Place Bound Bottom")
		(35 "F.Fab" user "Ref Des/Assembly Top")
		(33 "B.Fab" user "Ref Des/Assembly Bottom")
	)
	(footprint ""
		(layer "F.Cu")
		(at 379.4125 -36.5506)
		(property "Reference" "R8F35"
			(at 0 0 0)
			(layer "F.SilkS")
			(hide yes)
			(effects
				(font
					(size 1.27 1.27)
				)
			)
		)
		(property "Value" ""
			(at 0 0 0)
			(layer "F.Fab")
			(effects
				(font
					(size 1.27 1.27)
				)
			)
		)
		(duplicate_pad_numbers_are_jumpers no)
		(fp_poly
			(pts
				(xy -0.2794 -0.1016) (xy 0.2794 -0.1016) (xy 0.2794 0.9906) (xy -0.2794 0.9906)
			)
			(stroke
				(width 0)
				(type default)
			)
			(fill no)
			(layer "F.CrtYd")
		)
		(fp_line
			(start -0.2794 -0.1016)
			(end -0.2794 0.9906)
			(stroke
				(width 0.1)
				(type default)
			)
			(layer "F.Fab")
		)
		(fp_line
			(start -0.2794 0.9906)
			(end 0.2794 0.9906)
			(stroke
				(width 0.1)
				(type default)
			)
			(layer "F.Fab")
		)
		(fp_line
			(start 0.2794 -0.1016)
			(end -0.2794 -0.1016)
			(stroke
				(width 0.1)
				(type default)
			)
			(layer "F.Fab")
		)
		(fp_line
			(start 0.2794 0.9906)
			(end 0.2794 -0.1016)
			(stroke
				(width 0.1)
				(type default)
			)
			(layer "F.Fab")
		)
		(pad "1" smd rect
			(at 0 0)
			(size 0.508 0.508)
			(layers "F.Cu" "F.Mask" "F.Paste")
			(net "PU_SPI_BMC_BT_WP_N")
		)
		(pad "2" smd rect
			(at 0 0.889)
			(size 0.508 0.508)
			(layers "F.Cu" "F.Mask" "F.Paste")
			(net "GND")
		)
		(zone
			(layer "F.Cu")
			(hatch none 0.5)
			(connect_pads
				(clearance 0)
			)
			(min_thickness 0.25)
			(keepout
				(tracks allowed)
				(vias not_allowed)
				(pads allowed)
				(copperpour not_allowed)
				(footprints allowed)
			)
			(placement
				(enabled no)
				(sheetname "")
			)
			(fill
				(thermal_gap 0.5)
				(thermal_bridge_width 0.5)
				(island_removal_mode 0)
			)
			(polygon
				(pts
					(xy 379.1585 -36.2966) (xy 379.6665 -36.2966) (xy 379.6665 -35.9156) (xy 379.1585 -35.9156)
				)
			)
		)
		(zone
			(layer "F.Cu")
			(hatch none 0.5)
			(connect_pads
				(clearance 0)
			)
			(min_thickness 0.25)
			(keepout
				(tracks not_allowed)
				(vias allowed)
				(pads allowed)
				(copperpour not_allowed)
				(footprints allowed)
			)
			(placement
				(enabled no)
				(sheetname "")
			)
			(fill
				(thermal_gap 0.5)
				(thermal_bridge_width 0.5)
				(island_removal_mode 0)
			)
			(polygon
				(pts
					(xy 379.1585 -35.9156) (xy 379.6665 -35.9156) (xy 379.6665 -36.2966) (xy 379.1585 -36.2966)
				)
			)
		)
	)
	(footprint ""
		(layer "F.Cu")
		(at 29.495496 -27.150822 180)
		(property "Reference" "R12W14"
			(at 1.01473 0.656336 90)
			(unlocked yes)
			(layer "F.SilkS")
			(effects
				(font
					(size 0.4064 0.254)
					(thickness 0.1524)
				)
			)
		)
		(property "Value" ""
			(at 0 0 180)
			(layer "F.Fab")
			(effects
				(font
					(size 1.27 1.27)
				)
			)
		)
		(duplicate_pad_numbers_are_jumpers no)
		(fp_poly
			(pts
				(xy -0.4953 -0.2032) (xy 0.4953 -0.2032) (xy 0.4953 1.6002) (xy -0.4953 1.6002)
			)
			(stroke
				(width 0)
				(type default)
			)
			(fill no)
			(layer "F.CrtYd")
		)
		(fp_line
			(start 0.4953 1.6002)
			(end -0.4953 1.6002)
			(stroke
				(width 0.1)
				(type default)
			)
			(layer "F.Fab")
		)
		(fp_line
			(start 0.4953 -0.2032)
			(end 0.4953 1.6002)
			(stroke
				(width 0.1)
				(type default)
			)
			(layer "F.Fab")
		)
		(fp_line
			(start -0.4953 1.6002)
			(end -0.4953 -0.2032)
			(stroke
				(width 0.1)
				(type default)
			)
			(layer "F.Fab")
		)
		(fp_line
			(start -0.4953 -0.2032)
			(end 0.4953 -0.2032)
			(stroke
				(width 0.1)
				(type default)
			)
			(layer "F.Fab")
		)
		(pad "1" smd rect
			(at 0 0 180)
			(size 0.762 0.889)
			(layers "F.Cu" "F.Mask" "F.Paste")
			(net "P12V_NVDIMM_GHJ")
		)
		(pad "2" smd rect
			(at 0 1.397 180)
			(size 0.762 0.889)
			(layers "F.Cu" "F.Mask" "F.Paste")
			(net "PWRGD_PVDDQ_GHJ_N")
		)
		(zone
			(layer "F.Cu")
			(hatch none 0.5)
			(connect_pads
				(clearance 0)
			)
			(min_thickness 0.25)
			(keepout
				(tracks allowed)
				(vias not_allowed)
				(pads allowed)
				(copperpour not_allowed)
				(footprints allowed)
			)
			(placement
				(enabled no)
				(sheetname "")
			)
			(fill
				(thermal_gap 0.5)
				(thermal_bridge_width 0.5)
				(island_removal_mode 0)
			)
			(polygon
				(pts
					(xy 29.114496 -28.103322) (xy 29.114496 -27.595322) (xy 29.876496 -27.595322) (xy 29.876496 -28.103322)
				)
			)
		)
		(zone
			(layer "F.Cu")
			(hatch none 0.5)
			(connect_pads
				(clearance 0)
			)
			(min_thickness 0.25)
			(keepout
				(tracks not_allowed)
				(vias allowed)
				(pads allowed)
				(copperpour not_allowed)
				(footprints allowed)
			)
			(placement
				(enabled no)
				(sheetname "")
			)
			(fill
				(thermal_gap 0.5)
				(thermal_bridge_width 0.5)
				(island_removal_mode 0)
			)
			(polygon
				(pts
					(xy 29.876496 -28.103322) (xy 29.114496 -28.103322) (xy 29.114496 -27.595322) (xy 29.876496 -27.595322)
				)
			)
		)
	)
	(footprint ""
		(layer "F.Cu")
		(at 28.7528 -103.7844 90)
		(property "Reference" "R1C34"
			(at 0 0 90)
			(layer "F.SilkS")
			(hide yes)
			(effects
				(font
					(size 1.27 1.27)
				)
			)
		)
		(property "Value" ""
			(at 0 0 90)
			(layer "F.Fab")
			(effects
				(font
					(size 1.27 1.27)
				)
			)
		)
		(duplicate_pad_numbers_are_jumpers no)
		(fp_poly
			(pts
				(xy -0.2794 -0.1016) (xy 0.2794 -0.1016) (xy 0.2794 0.9906) (xy -0.2794 0.9906)
			)
			(stroke
				(width 0)
				(type default)
			)
			(fill no)
			(layer "F.CrtYd")
		)
		(fp_line
			(start 0.2794 -0.1016)
			(end -0.2794 -0.1016)
			(stroke
				(width 0.1)
				(type default)
			)
			(layer "F.Fab")
		)
		(fp_line
			(start -0.2794 -0.1016)
			(end -0.2794 0.9906)
			(stroke
				(width 0.1)
				(type default)
			)
			(layer "F.Fab")
		)
		(fp_line
			(start 0.2794 0.9906)
			(end 0.2794 -0.1016)
			(stroke
				(width 0.1)
				(type default)
			)
			(layer "F.Fab")
		)
		(fp_line
			(start -0.2794 0.9906)
			(end 0.2794 0.9906)
			(stroke
				(width 0.1)
				(type default)
			)
			(layer "F.Fab")
		)
		(pad "1" smd rect
			(at 0 0 90)
			(size 0.508 0.508)
			(layers "F.Cu" "F.Mask" "F.Paste")
			(net "P3V3_STBY")
		)
		(pad "2" smd rect
			(at 0 0.889 90)
			(size 0.508 0.508)
			(layers "F.Cu" "F.Mask" "F.Paste")
			(net "PU_PIROM_CPU1_ADDR0")
		)
		(zone
			(layer "F.Cu")
			(hatch none 0.5)
			(connect_pads
				(clearance 0)
			)
			(min_thickness 0.25)
			(keepout
				(tracks allowed)
				(vias not_allowed)
				(pads allowed)
				(copperpour not_allowed)
				(footprints allowed)
			)
			(placement
				(enabled no)
				(sheetname "")
			)
			(fill
				(thermal_gap 0.5)
				(thermal_bridge_width 0.5)
				(island_removal_mode 0)
			)
			(polygon
				(pts
					(xy 29.0068 -103.5304) (xy 29.0068 -104.0384) (xy 29.3878 -104.0384) (xy 29.3878 -103.5304)
				)
			)
		)
		(zone
			(layer "F.Cu")
			(hatch none 0.5)
			(connect_pads
				(clearance 0)
			)
			(min_thickness 0.25)
			(keepout
				(tracks not_allowed)
				(vias allowed)
				(pads allowed)
				(copperpour not_allowed)
				(footprints allowed)
			)
			(placement
				(enabled no)
				(sheetname "")
			)
			(fill
				(thermal_gap 0.5)
				(thermal_bridge_width 0.5)
				(island_removal_mode 0)
			)
			(polygon
				(pts
					(xy 29.3878 -103.5304) (xy 29.3878 -104.0384) (xy 29.0068 -104.0384) (xy 29.0068 -103.5304)
				)
			)
		)
	)
)
